FILE_TYPE = CONNECTIVITY;
{Allegro Design Entry HDL 17.4-2019 S026 (4007227) 1/17/2022}
"PAGE_NUMBER" = 69;
0"NC";
1"GND\g";
2"PVDDCR_SOC_P0\g";
3"GND\g";
4"PVDDCR_SOC_P0\g";
5"GND\g";
6"PVDDCR_SOC_P0\g";
7"GND\g";
8"PVDDCR_SOC_P0\g";
9"GND\g";
10"PVDDCR_SOC_P0\g";
11"GND\g";
12"PVDDCR_SOC_P0\g";
13"GND\g";
14"PVDDCR_SOC_P0\g";
15"PVDDCR_SOC_P0\g";
16"GND\g";
17"PVDD11_S3_P0\g";
18"GND\g";
19"PVDD11_S3_P0\g";
20"GND\g";
21"PVDD11_S3_P0\g";
22"GND\g";
23"PVDD11_S3_P0\g";
24"GND\g";
25"PVDD11_S3_P0\g";
26"GND\g";
27"PVDDIO_P0\g";
28"GND\g";
29"PVDDIO_P0\g";
30"GND\g";
31"PVDDIO_P0\g";
32"GND\g";
%"Q_CAP"
"1","(-9075,875)","0","pure_quanta","I1";
;
LOCATION"C3925"
$SEC"1"
CDS_SEC"1"
MATERIAL"X6S"
TOLERANCE"20%"
VALUE"22UF"
VOLTAGE"4V"
PACK_TYPE"C0402"
CDS_LIB"pure_quanta"
PART_NUMBER"CH622KMEB02";
"B"
$PN"2"1;
"A"
$PN"1"4;
%"Q_CAP"
"1","(-8625,2300)","0","pure_quanta","I10";
;
LOCATION"C2539"
$SEC"1"
CDS_SEC"1"
MATERIAL"X6S"
TOLERANCE"20%"
VALUE"22UF"
VOLTAGE"4V"
PACK_TYPE"C0402"
CDS_LIB"pure_quanta"
PART_NUMBER"CH622KMEB02";
"B"
$PN"2"7;
"A"
$PN"1"6;
%"UNIVERSAL_GND"
"1","(-5100,4775)","0","pure_quanta_power","I100";
;
CDS_LIB"pure_quanta_power"
HDL_POWER"GND";
"A"11;
%"Q_CAP"
"1","(-5100,5150)","0","pure_quanta","I101";
;
LOCATION"C2591"
$SEC"1"
CDS_SEC"1"
MATERIAL"X6S"
TOLERANCE"20%"
VALUE"22UF"
VOLTAGE"4V"
PACK_TYPE"C0402"
CDS_LIB"pure_quanta"
PART_NUMBER"CH622KMEB02";
"B"
$PN"2"11;
"A"
$PN"1"14;
%"Q_CAP"
"1","(-4500,4325)","0","pure_quanta","I102";
;
LOCATION"C2599"
$SEC"1"
CDS_SEC"1"
MATERIAL"X6S"
TOLERANCE"20%"
VALUE"22UF"
VOLTAGE"4V"
PACK_TYPE"C0402"
CDS_LIB"pure_quanta"
PART_NUMBER"CH622KMEB02";
"B"
$PN"2"32;
"A"
$PN"1"31;
%"UNIVERSAL_POWER"
"1","(-4500,4600)","0","pure_quanta_power","I103";
;
HDL_POWER"PVDDIO_P0"
CDS_LIB"pure_quanta_power";
"A"31;
%"Q_CAP"
"1","(-4525,5100)","0","pure_quanta","I104";
;
LOCATION"C2598"
$SEC"1"
CDS_SEC"1"
MATERIAL"X6S"
TOLERANCE"20%"
VALUE"22UF"
VOLTAGE"4V"
PACK_TYPE"C0402"
CDS_LIB"pure_quanta"
PART_NUMBER"CH622KMEB02";
"B"
$PN"2"28;
"A"
$PN"1"27;
%"UNIVERSAL_GND"
"1","(-5100,5525)","0","pure_quanta_power","I105";
;
CDS_LIB"pure_quanta_power"
HDL_POWER"GND";
"A"16;
%"Q_CAP"
"1","(-5100,5900)","0","pure_quanta","I106";
;
LOCATION"C2590"
$SEC"1"
CDS_SEC"1"
MATERIAL"X6S"
TOLERANCE"20%"
VALUE"22UF"
VOLTAGE"4V"
PACK_TYPE"C0402"
CDS_LIB"pure_quanta"
PART_NUMBER"CH622KMEB02";
"B"
$PN"2"16;
"A"
$PN"1"15;
%"UNIVERSAL_POWER"
"1","(-4525,5375)","0","pure_quanta_power","I107";
;
HDL_POWER"PVDDIO_P0"
CDS_LIB"pure_quanta_power";
"A"27;
%"Q_CAP"
"1","(-4525,5900)","0","pure_quanta","I108";
;
LOCATION"C2597"
$SEC"1"
CDS_SEC"1"
MATERIAL"X6S"
TOLERANCE"20%"
VALUE"22UF"
VOLTAGE"4V"
PACK_TYPE"C0402"
CDS_LIB"pure_quanta"
PART_NUMBER"CH622KMEB02";
"B"
$PN"2"30;
"A"
$PN"1"29;
%"UNIVERSAL_POWER"
"1","(-4525,6175)","0","pure_quanta_power","I109";
;
HDL_POWER"PVDDIO_P0"
CDS_LIB"pure_quanta_power";
"A"29;
%"Q_CAP"
"1","(-8625,3000)","0","pure_quanta","I11";
;
LOCATION"C2538"
$SEC"1"
CDS_SEC"1"
MATERIAL"X6S"
TOLERANCE"20%"
VALUE"22UF"
VOLTAGE"4V"
PACK_TYPE"C0402"
CDS_LIB"pure_quanta"
PART_NUMBER"CH622KMEB02";
"B"
$PN"2"5;
"A"
$PN"1"10;
%"UNIVERSAL_GND"
"1","(-4050,475)","0","pure_quanta_power","I110";
;
CDS_LIB"pure_quanta_power"
HDL_POWER"GND";
"A"26;
%"Q_CAP"
"1","(-4050,800)","0","pure_quanta","I111";
;
LOCATION"C3933"
$SEC"1"
CDS_SEC"1"
MATERIAL"X6S"
TOLERANCE"20%"
VALUE"22UF"
VOLTAGE"4V"
PACK_TYPE"C0402"
CDS_LIB"pure_quanta"
PART_NUMBER"CH622KMEB02";
"B"
$PN"2"26;
"A"
$PN"1"25;
%"Q_CAP"
"1","(-4050,1400)","0","pure_quanta","I112";
;
LOCATION"C2610"
$SEC"1"
CDS_SEC"1"
MATERIAL"X6S"
TOLERANCE"20%"
VALUE"22UF"
VOLTAGE"4V"
PACK_TYPE"C0402"
CDS_LIB"pure_quanta"
PART_NUMBER"CH622KMEB02";
"B"
$PN"2"24;
"A"
$PN"1"23;
%"Q_CAP"
"1","(-4050,2000)","0","pure_quanta","I113";
;
LOCATION"C2609"
$SEC"1"
CDS_SEC"1"
MATERIAL"X6S"
TOLERANCE"20%"
VALUE"22UF"
VOLTAGE"4V"
PACK_TYPE"C0402"
CDS_LIB"pure_quanta"
PART_NUMBER"CH622KMEB02";
"B"
$PN"2"22;
"A"
$PN"1"21;
%"Q_CAP"
"1","(-3600,1400)","0","pure_quanta","I114";
;
LOCATION"C2617"
$SEC"1"
CDS_SEC"1"
MATERIAL"X6S"
TOLERANCE"20%"
VALUE"22UF"
VOLTAGE"4V"
PACK_TYPE"C0402"
CDS_LIB"pure_quanta"
PART_NUMBER"CH622KMEB02";
"B"
$PN"2"24;
"A"
$PN"1"23;
%"Q_CAP"
"1","(-3600,2000)","0","pure_quanta","I115";
;
LOCATION"C2616"
$SEC"1"
CDS_SEC"1"
MATERIAL"X6S"
TOLERANCE"20%"
VALUE"22UF"
VOLTAGE"4V"
PACK_TYPE"C0402"
CDS_LIB"pure_quanta"
PART_NUMBER"CH622KMEB02";
"B"
$PN"2"22;
"A"
$PN"1"21;
%"Q_CAP"
"1","(-3150,1400)","0","pure_quanta","I116";
;
LOCATION"C2624"
$SEC"1"
CDS_SEC"1"
MATERIAL"X6S"
TOLERANCE"20%"
VALUE"22UF"
VOLTAGE"4V"
PACK_TYPE"C0402"
CDS_LIB"pure_quanta"
PART_NUMBER"CH622KMEB02";
"B"
$PN"2"24;
"A"
$PN"1"23;
%"Q_CAP"
"1","(-3150,2000)","0","pure_quanta","I117";
;
LOCATION"C2623"
$SEC"1"
CDS_SEC"1"
MATERIAL"X6S"
TOLERANCE"20%"
VALUE"22UF"
VOLTAGE"4V"
PACK_TYPE"C0402"
CDS_LIB"pure_quanta"
PART_NUMBER"CH622KMEB02";
"B"
$PN"2"22;
"A"
$PN"1"21;
%"Q_CAP"
"1","(-2700,1400)","0","pure_quanta","I118";
;
LOCATION"C2630"
$SEC"1"
CDS_SEC"1"
MATERIAL"X6S"
TOLERANCE"20%"
VALUE"22UF"
VOLTAGE"4V"
PACK_TYPE"C0402"
CDS_LIB"pure_quanta"
PART_NUMBER"CH622KMEB02";
"B"
$PN"2"24;
"A"
$PN"1"23;
%"Q_CAP"
"1","(-2700,2000)","0","pure_quanta","I119";
;
LOCATION"C2629"
$SEC"1"
CDS_SEC"1"
MATERIAL"X6S"
TOLERANCE"20%"
VALUE"22UF"
VOLTAGE"4V"
PACK_TYPE"C0402"
CDS_LIB"pure_quanta"
PART_NUMBER"CH622KMEB02";
"B"
$PN"2"22;
"A"
$PN"1"21;
%"UNIVERSAL_POWER"
"1","(-9075,3275)","0","pure_quanta_power","I12";
;
HDL_POWER"PVDDCR_SOC_P0"
CDS_LIB"pure_quanta_power";
"A"10;
%"Q_CAP"
"1","(-2250,1400)","0","pure_quanta","I120";
;
LOCATION"C2636"
$SEC"1"
CDS_SEC"1"
MATERIAL"X6S"
TOLERANCE"20%"
VALUE"22UF"
VOLTAGE"4V"
PACK_TYPE"C0402"
CDS_LIB"pure_quanta"
PART_NUMBER"CH622KMEB02";
"B"
$PN"2"24;
"A"
$PN"1"23;
%"Q_CAP"
"1","(-2250,2000)","0","pure_quanta","I121";
;
LOCATION"C2635"
$SEC"1"
CDS_SEC"1"
MATERIAL"X6S"
TOLERANCE"20%"
VALUE"22UF"
VOLTAGE"4V"
PACK_TYPE"C0402"
CDS_LIB"pure_quanta"
PART_NUMBER"CH622KMEB02";
"B"
$PN"2"22;
"A"
$PN"1"21;
%"Q_CAP"
"1","(-4050,2625)","0","pure_quanta","I122";
;
LOCATION"C2608"
$SEC"1"
CDS_SEC"1"
MATERIAL"X6S"
TOLERANCE"20%"
VALUE"22UF"
VOLTAGE"4V"
PACK_TYPE"C0402"
CDS_LIB"pure_quanta"
PART_NUMBER"CH622KMEB02";
"B"
$PN"2"20;
"A"
$PN"1"19;
%"Q_CAP"
"1","(-3600,2625)","0","pure_quanta","I123";
;
LOCATION"C2615"
$SEC"1"
CDS_SEC"1"
MATERIAL"X6S"
TOLERANCE"20%"
VALUE"22UF"
VOLTAGE"4V"
PACK_TYPE"C0402"
CDS_LIB"pure_quanta"
PART_NUMBER"CH622KMEB02";
"B"
$PN"2"20;
"A"
$PN"1"19;
%"Q_CAP"
"1","(-4050,3275)","0","pure_quanta","I124";
;
LOCATION"C2607"
$SEC"1"
CDS_SEC"1"
MATERIAL"X6S"
TOLERANCE"20%"
VALUE"22UF"
VOLTAGE"4V"
PACK_TYPE"C0402"
CDS_LIB"pure_quanta"
PART_NUMBER"CH622KMEB02";
"B"
$PN"2"18;
"A"
$PN"1"17;
%"Q_CAP"
"1","(-3600,3275)","0","pure_quanta","I125";
;
LOCATION"C2614"
$SEC"1"
CDS_SEC"1"
MATERIAL"X6S"
TOLERANCE"20%"
VALUE"22UF"
VOLTAGE"4V"
PACK_TYPE"C0402"
CDS_LIB"pure_quanta"
PART_NUMBER"CH622KMEB02";
"B"
$PN"2"18;
"A"
$PN"1"17;
%"Q_CAP"
"1","(-3150,2625)","0","pure_quanta","I126";
;
LOCATION"C2622"
$SEC"1"
CDS_SEC"1"
MATERIAL"X6S"
TOLERANCE"20%"
VALUE"22UF"
VOLTAGE"4V"
PACK_TYPE"C0402"
CDS_LIB"pure_quanta"
PART_NUMBER"CH622KMEB02";
"B"
$PN"2"20;
"A"
$PN"1"19;
%"Q_CAP"
"1","(-3150,3275)","0","pure_quanta","I127";
;
LOCATION"C2621"
$SEC"1"
CDS_SEC"1"
MATERIAL"X6S"
TOLERANCE"20%"
VALUE"22UF"
VOLTAGE"4V"
PACK_TYPE"C0402"
CDS_LIB"pure_quanta"
PART_NUMBER"CH622KMEB02";
"B"
$PN"2"18;
"A"
$PN"1"17;
%"UNIVERSAL_GND"
"1","(-3150,3950)","0","pure_quanta_power","I128";
;
CDS_LIB"pure_quanta_power"
HDL_POWER"GND";
"A"32;
%"Q_CAP"
"1","(-2700,2625)","0","pure_quanta","I129";
;
LOCATION"C2628"
$SEC"1"
CDS_SEC"1"
MATERIAL"X6S"
TOLERANCE"20%"
VALUE"22UF"
VOLTAGE"4V"
PACK_TYPE"C0402"
CDS_LIB"pure_quanta"
PART_NUMBER"CH622KMEB02";
"B"
$PN"2"20;
"A"
$PN"1"19;
%"Q_CAP"
"1","(-9075,3725)","0","pure_quanta","I13";
;
LOCATION"C2530"
$SEC"1"
CDS_SEC"1"
MATERIAL"X6S"
TOLERANCE"20%"
VALUE"22UF"
VOLTAGE"4V"
PACK_TYPE"C0402"
CDS_LIB"pure_quanta"
PART_NUMBER"CH622KMEB02";
"B"
$PN"2"9;
"A"
$PN"1"8;
%"Q_CAP"
"1","(-2250,2625)","0","pure_quanta","I130";
;
LOCATION"C2634"
$SEC"1"
CDS_SEC"1"
MATERIAL"X6S"
TOLERANCE"20%"
VALUE"22UF"
VOLTAGE"4V"
PACK_TYPE"C0402"
CDS_LIB"pure_quanta"
PART_NUMBER"CH622KMEB02";
"B"
$PN"2"20;
"A"
$PN"1"19;
%"Q_CAP"
"1","(-2700,3275)","0","pure_quanta","I131";
;
LOCATION"C2627"
$SEC"1"
CDS_SEC"1"
MATERIAL"X6S"
TOLERANCE"20%"
VALUE"22UF"
VOLTAGE"4V"
PACK_TYPE"C0402"
CDS_LIB"pure_quanta"
PART_NUMBER"CH622KMEB02";
"B"
$PN"2"18;
"A"
$PN"1"17;
%"Q_CAP"
"1","(-2250,3275)","0","pure_quanta","I132";
;
LOCATION"C2633"
$SEC"1"
CDS_SEC"1"
MATERIAL"X6S"
TOLERANCE"20%"
VALUE"22UF"
VOLTAGE"4V"
PACK_TYPE"C0402"
CDS_LIB"pure_quanta"
PART_NUMBER"CH622KMEB02";
"B"
$PN"2"18;
"A"
$PN"1"17;
%"Q_CAP"
"1","(-1800,1400)","0","pure_quanta","I133";
;
LOCATION"C2642"
$SEC"1"
CDS_SEC"1"
MATERIAL"X6S"
TOLERANCE"20%"
VALUE"22UF"
VOLTAGE"4V"
PACK_TYPE"C0402"
CDS_LIB"pure_quanta"
PART_NUMBER"CH622KMEB02";
"B"
$PN"2"24;
"A"
$PN"1"23;
%"Q_CAP"
"1","(-1800,2000)","0","pure_quanta","I134";
;
LOCATION"C2641"
$SEC"1"
CDS_SEC"1"
MATERIAL"X6S"
TOLERANCE"20%"
VALUE"22UF"
VOLTAGE"4V"
PACK_TYPE"C0402"
CDS_LIB"pure_quanta"
PART_NUMBER"CH622KMEB02";
"B"
$PN"2"22;
"A"
$PN"1"21;
%"Q_CAP"
"1","(-1350,1400)","0","pure_quanta","I135";
;
LOCATION"C2648"
$SEC"1"
CDS_SEC"1"
MATERIAL"X6S"
TOLERANCE"20%"
VALUE"22UF"
VOLTAGE"4V"
PACK_TYPE"C0402"
CDS_LIB"pure_quanta"
PART_NUMBER"CH622KMEB02";
"B"
$PN"2"24;
"A"
$PN"1"23;
%"Q_CAP"
"1","(-1350,2000)","0","pure_quanta","I136";
;
LOCATION"C2647"
$SEC"1"
CDS_SEC"1"
MATERIAL"X6S"
TOLERANCE"20%"
VALUE"22UF"
VOLTAGE"4V"
PACK_TYPE"C0402"
CDS_LIB"pure_quanta"
PART_NUMBER"CH622KMEB02";
"B"
$PN"2"22;
"A"
$PN"1"21;
%"UNIVERSAL_GND"
"1","(-500,1025)","0","pure_quanta_power","I137";
;
CDS_LIB"pure_quanta_power"
HDL_POWER"GND";
"A"24;
%"Q_CAP"
"1","(-900,1400)","0","pure_quanta","I138";
;
LOCATION"C3934"
$SEC"1"
CDS_SEC"1"
MATERIAL"X6S"
TOLERANCE"20%"
VALUE"22UF"
VOLTAGE"4V"
PACK_TYPE"C0402"
CDS_LIB"pure_quanta"
PART_NUMBER"CH622KMEB02";
"B"
$PN"2"24;
"A"
$PN"1"23;
%"Q_CAP"
"1","(-900,2000)","0","pure_quanta","I139";
;
LOCATION"C2653"
$SEC"1"
CDS_SEC"1"
MATERIAL"X6S"
TOLERANCE"20%"
VALUE"22UF"
VOLTAGE"4V"
PACK_TYPE"C0402"
CDS_LIB"pure_quanta"
PART_NUMBER"CH622KMEB02";
"B"
$PN"2"22;
"A"
$PN"1"21;
%"UNIVERSAL_POWER"
"1","(-9075,4000)","0","pure_quanta_power","I14";
;
HDL_POWER"PVDDCR_SOC_P0"
CDS_LIB"pure_quanta_power";
"A"8;
%"Q_CAP"
"1","(-500,1400)","0","pure_quanta","I140";
;
LOCATION"C3935"
$SEC"1"
CDS_SEC"1"
MATERIAL"X6S"
TOLERANCE"20%"
VALUE"22UF"
VOLTAGE"4V"
PACK_TYPE"C0402"
CDS_LIB"pure_quanta"
PART_NUMBER"CH622KMEB02";
"B"
$PN"2"24;
"A"
$PN"1"23;
%"UNIVERSAL_GND"
"1","(-500,1625)","0","pure_quanta_power","I141";
;
CDS_LIB"pure_quanta_power"
HDL_POWER"GND";
"A"22;
%"Q_CAP"
"1","(-500,2000)","0","pure_quanta","I142";
;
LOCATION"C2658"
$SEC"1"
CDS_SEC"1"
MATERIAL"X6S"
TOLERANCE"20%"
VALUE"22UF"
VOLTAGE"4V"
PACK_TYPE"C0402"
CDS_LIB"pure_quanta"
PART_NUMBER"CH622KMEB02";
"B"
$PN"2"22;
"A"
$PN"1"21;
%"Q_CAP"
"1","(-1800,2625)","0","pure_quanta","I143";
;
LOCATION"C2640"
$SEC"1"
CDS_SEC"1"
MATERIAL"X6S"
TOLERANCE"20%"
VALUE"22UF"
VOLTAGE"4V"
PACK_TYPE"C0402"
CDS_LIB"pure_quanta"
PART_NUMBER"CH622KMEB02";
"B"
$PN"2"20;
"A"
$PN"1"19;
%"Q_CAP"
"1","(-1350,2625)","0","pure_quanta","I144";
;
LOCATION"C2646"
$SEC"1"
CDS_SEC"1"
MATERIAL"X6S"
TOLERANCE"20%"
VALUE"22UF"
VOLTAGE"4V"
PACK_TYPE"C0402"
CDS_LIB"pure_quanta"
PART_NUMBER"CH622KMEB02";
"B"
$PN"2"20;
"A"
$PN"1"19;
%"Q_CAP"
"1","(-1800,3275)","0","pure_quanta","I145";
;
LOCATION"C2639"
$SEC"1"
CDS_SEC"1"
MATERIAL"X6S"
TOLERANCE"20%"
VALUE"22UF"
VOLTAGE"4V"
PACK_TYPE"C0402"
CDS_LIB"pure_quanta"
PART_NUMBER"CH622KMEB02";
"B"
$PN"2"18;
"A"
$PN"1"17;
%"Q_CAP"
"1","(-1350,3275)","0","pure_quanta","I146";
;
LOCATION"C2645"
$SEC"1"
CDS_SEC"1"
MATERIAL"X6S"
TOLERANCE"20%"
VALUE"22UF"
VOLTAGE"4V"
PACK_TYPE"C0402"
CDS_LIB"pure_quanta"
PART_NUMBER"CH622KMEB02";
"B"
$PN"2"18;
"A"
$PN"1"17;
%"Q_CAP"
"1","(-900,2625)","0","pure_quanta","I147";
;
LOCATION"C2652"
$SEC"1"
CDS_SEC"1"
MATERIAL"X6S"
TOLERANCE"20%"
VALUE"22UF"
VOLTAGE"4V"
PACK_TYPE"C0402"
CDS_LIB"pure_quanta"
PART_NUMBER"CH622KMEB02";
"B"
$PN"2"20;
"A"
$PN"1"19;
%"UNIVERSAL_GND"
"1","(-500,2275)","0","pure_quanta_power","I148";
;
CDS_LIB"pure_quanta_power"
HDL_POWER"GND";
"A"20;
%"Q_CAP"
"1","(-500,2625)","0","pure_quanta","I149";
;
LOCATION"C2657"
$SEC"1"
CDS_SEC"1"
MATERIAL"X6S"
TOLERANCE"20%"
VALUE"22UF"
VOLTAGE"4V"
PACK_TYPE"C0402"
CDS_LIB"pure_quanta"
PART_NUMBER"CH622KMEB02";
"B"
$PN"2"20;
"A"
$PN"1"19;
%"Q_CAP"
"1","(-8625,3725)","0","pure_quanta","I15";
;
LOCATION"C2537"
$SEC"1"
CDS_SEC"1"
MATERIAL"X6S"
TOLERANCE"20%"
VALUE"22UF"
VOLTAGE"4V"
PACK_TYPE"C0402"
CDS_LIB"pure_quanta"
PART_NUMBER"CH622KMEB02";
"B"
$PN"2"9;
"A"
$PN"1"8;
%"UNIVERSAL_GND"
"1","(-500,2900)","0","pure_quanta_power","I150";
;
CDS_LIB"pure_quanta_power"
HDL_POWER"GND";
"A"18;
%"Q_CAP"
"1","(-900,3275)","0","pure_quanta","I151";
;
LOCATION"C2651"
$SEC"1"
CDS_SEC"1"
MATERIAL"X6S"
TOLERANCE"20%"
VALUE"22UF"
VOLTAGE"4V"
PACK_TYPE"C0402"
CDS_LIB"pure_quanta"
PART_NUMBER"CH622KMEB02";
"B"
$PN"2"18;
"A"
$PN"1"17;
%"Q_CAP"
"1","(-500,3275)","0","pure_quanta","I152";
;
LOCATION"C2656"
$SEC"1"
CDS_SEC"1"
MATERIAL"X6S"
TOLERANCE"20%"
VALUE"22UF"
VOLTAGE"4V"
PACK_TYPE"C0402"
CDS_LIB"pure_quanta"
PART_NUMBER"CH622KMEB02";
"B"
$PN"2"18;
"A"
$PN"1"17;
%"Q_CAP"
"1","(-4050,4325)","0","pure_quanta","I153";
;
LOCATION"C2606"
$SEC"1"
CDS_SEC"1"
MATERIAL"X6S"
TOLERANCE"20%"
VALUE"22UF"
VOLTAGE"4V"
PACK_TYPE"C0402"
CDS_LIB"pure_quanta"
PART_NUMBER"CH622KMEB02";
"B"
$PN"2"32;
"A"
$PN"1"31;
%"Q_CAP"
"1","(-4075,5100)","0","pure_quanta","I154";
;
LOCATION"C2605"
$SEC"1"
CDS_SEC"1"
MATERIAL"X6S"
TOLERANCE"20%"
VALUE"22UF"
VOLTAGE"4V"
PACK_TYPE"C0402"
CDS_LIB"pure_quanta"
PART_NUMBER"CH622KMEB02";
"B"
$PN"2"28;
"A"
$PN"1"27;
%"Q_CAP"
"1","(-3600,4325)","0","pure_quanta","I155";
;
LOCATION"C2613"
$SEC"1"
CDS_SEC"1"
MATERIAL"X6S"
TOLERANCE"20%"
VALUE"22UF"
VOLTAGE"4V"
PACK_TYPE"C0402"
CDS_LIB"pure_quanta"
PART_NUMBER"CH622KMEB02";
"B"
$PN"2"32;
"A"
$PN"1"31;
%"Q_CAP"
"1","(-3625,5100)","0","pure_quanta","I156";
;
LOCATION"C2612"
$SEC"1"
CDS_SEC"1"
MATERIAL"X6S"
TOLERANCE"20%"
VALUE"22UF"
VOLTAGE"4V"
PACK_TYPE"C0402"
CDS_LIB"pure_quanta"
PART_NUMBER"CH622KMEB02";
"B"
$PN"2"28;
"A"
$PN"1"27;
%"Q_CAP"
"1","(-3175,5100)","0","pure_quanta","I157";
;
LOCATION"C2619"
$SEC"1"
CDS_SEC"1"
MATERIAL"X6S"
TOLERANCE"20%"
VALUE"22UF"
VOLTAGE"4V"
PACK_TYPE"C0402"
CDS_LIB"pure_quanta"
PART_NUMBER"CH622KMEB02";
"B"
$PN"2"28;
"A"
$PN"1"27;
%"Q_CAP"
"1","(-4075,5900)","0","pure_quanta","I158";
;
LOCATION"C2604"
$SEC"1"
CDS_SEC"1"
MATERIAL"X6S"
TOLERANCE"20%"
VALUE"22UF"
VOLTAGE"4V"
PACK_TYPE"C0402"
CDS_LIB"pure_quanta"
PART_NUMBER"CH622KMEB02";
"B"
$PN"2"30;
"A"
$PN"1"29;
%"Q_CAP"
"1","(-3625,5900)","0","pure_quanta","I159";
;
LOCATION"C2611"
$SEC"1"
CDS_SEC"1"
MATERIAL"X6S"
TOLERANCE"20%"
VALUE"22UF"
VOLTAGE"4V"
PACK_TYPE"C0402"
CDS_LIB"pure_quanta"
PART_NUMBER"CH622KMEB02";
"B"
$PN"2"30;
"A"
$PN"1"29;
%"Q_CAP"
"1","(-9100,4425)","0","pure_quanta","I16";
;
LOCATION"C2529"
$SEC"1"
CDS_SEC"1"
MATERIAL"X6S"
TOLERANCE"20%"
VALUE"22UF"
VOLTAGE"4V"
PACK_TYPE"C0402"
CDS_LIB"pure_quanta"
PART_NUMBER"CH622KMEB02";
"B"
$PN"2"13;
"A"
$PN"1"12;
%"Q_CAP"
"1","(-3175,5900)","0","pure_quanta","I160";
;
LOCATION"C2618"
$SEC"1"
CDS_SEC"1"
MATERIAL"X6S"
TOLERANCE"20%"
VALUE"22UF"
VOLTAGE"4V"
PACK_TYPE"C0402"
CDS_LIB"pure_quanta"
PART_NUMBER"CH622KMEB02";
"B"
$PN"2"30;
"A"
$PN"1"29;
%"Q_CAP"
"1","(-3150,4325)","0","pure_quanta","I161";
;
LOCATION"C2620"
$SEC"1"
CDS_SEC"1"
MATERIAL"X6S"
TOLERANCE"20%"
VALUE"22UF"
VOLTAGE"4V"
PACK_TYPE"C0402"
CDS_LIB"pure_quanta"
PART_NUMBER"CH622KMEB02";
"B"
$PN"2"32;
"A"
$PN"1"31;
%"Q_CAP"
"1","(-2725,5100)","0","pure_quanta","I162";
;
LOCATION"C2626"
$SEC"1"
CDS_SEC"1"
MATERIAL"X6S"
TOLERANCE"20%"
VALUE"22UF"
VOLTAGE"4V"
PACK_TYPE"C0402"
CDS_LIB"pure_quanta"
PART_NUMBER"CH622KMEB02";
"B"
$PN"2"28;
"A"
$PN"1"27;
%"Q_CAP"
"1","(-2275,5100)","0","pure_quanta","I163";
;
LOCATION"C2632"
$SEC"1"
CDS_SEC"1"
MATERIAL"X6S"
TOLERANCE"20%"
VALUE"22UF"
VOLTAGE"4V"
PACK_TYPE"C0402"
CDS_LIB"pure_quanta"
PART_NUMBER"CH622KMEB02";
"B"
$PN"2"28;
"A"
$PN"1"27;
%"Q_CAP"
"1","(-2725,5900)","0","pure_quanta","I164";
;
LOCATION"C2625"
$SEC"1"
CDS_SEC"1"
MATERIAL"X6S"
TOLERANCE"20%"
VALUE"22UF"
VOLTAGE"4V"
PACK_TYPE"C0402"
CDS_LIB"pure_quanta"
PART_NUMBER"CH622KMEB02";
"B"
$PN"2"30;
"A"
$PN"1"29;
%"Q_CAP"
"1","(-2275,5900)","0","pure_quanta","I165";
;
LOCATION"C2631"
$SEC"1"
CDS_SEC"1"
MATERIAL"X6S"
TOLERANCE"20%"
VALUE"22UF"
VOLTAGE"4V"
PACK_TYPE"C0402"
CDS_LIB"pure_quanta"
PART_NUMBER"CH622KMEB02";
"B"
$PN"2"30;
"A"
$PN"1"29;
%"Q_CAP"
"1","(-1825,5100)","0","pure_quanta","I166";
;
LOCATION"C2638"
$SEC"1"
CDS_SEC"1"
MATERIAL"X6S"
TOLERANCE"20%"
VALUE"22UF"
VOLTAGE"4V"
PACK_TYPE"C0402"
CDS_LIB"pure_quanta"
PART_NUMBER"CH622KMEB02";
"B"
$PN"2"28;
"A"
$PN"1"27;
%"Q_CAP"
"1","(-1375,5100)","0","pure_quanta","I167";
;
LOCATION"C2644"
$SEC"1"
CDS_SEC"1"
MATERIAL"X6S"
TOLERANCE"20%"
VALUE"22UF"
VOLTAGE"4V"
PACK_TYPE"C0402"
CDS_LIB"pure_quanta"
PART_NUMBER"CH622KMEB02";
"B"
$PN"2"28;
"A"
$PN"1"27;
%"Q_CAP"
"1","(-1825,5900)","0","pure_quanta","I168";
;
LOCATION"C2637"
$SEC"1"
CDS_SEC"1"
MATERIAL"X6S"
TOLERANCE"20%"
VALUE"22UF"
VOLTAGE"4V"
PACK_TYPE"C0402"
CDS_LIB"pure_quanta"
PART_NUMBER"CH622KMEB02";
"B"
$PN"2"30;
"A"
$PN"1"29;
%"Q_CAP"
"1","(-1375,5900)","0","pure_quanta","I169";
;
LOCATION"C2643"
$SEC"1"
CDS_SEC"1"
MATERIAL"X6S"
TOLERANCE"20%"
VALUE"22UF"
VOLTAGE"4V"
PACK_TYPE"C0402"
CDS_LIB"pure_quanta"
PART_NUMBER"CH622KMEB02";
"B"
$PN"2"30;
"A"
$PN"1"29;
%"UNIVERSAL_POWER"
"1","(-9100,4700)","0","pure_quanta_power","I17";
;
HDL_POWER"PVDDCR_SOC_P0"
CDS_LIB"pure_quanta_power";
"A"12;
%"Q_CAP"
"1","(-925,5100)","0","pure_quanta","I170";
;
LOCATION"C2650"
$SEC"1"
CDS_SEC"1"
MATERIAL"X6S"
TOLERANCE"20%"
VALUE"22UF"
VOLTAGE"4V"
PACK_TYPE"C0402"
CDS_LIB"pure_quanta"
PART_NUMBER"CH622KMEB02";
"B"
$PN"2"28;
"A"
$PN"1"27;
%"UNIVERSAL_GND"
"1","(-525,4725)","0","pure_quanta_power","I171";
;
CDS_LIB"pure_quanta_power"
HDL_POWER"GND";
"A"28;
%"Q_CAP"
"1","(-525,5100)","0","pure_quanta","I172";
;
LOCATION"C2655"
$SEC"1"
CDS_SEC"1"
MATERIAL"X6S"
TOLERANCE"20%"
VALUE"22UF"
VOLTAGE"4V"
PACK_TYPE"C0402"
CDS_LIB"pure_quanta"
PART_NUMBER"CH622KMEB02";
"B"
$PN"2"28;
"A"
$PN"1"27;
%"Q_CAP"
"1","(-925,5900)","0","pure_quanta","I173";
;
LOCATION"C2649"
$SEC"1"
CDS_SEC"1"
MATERIAL"X6S"
TOLERANCE"20%"
VALUE"22UF"
VOLTAGE"4V"
PACK_TYPE"C0402"
CDS_LIB"pure_quanta"
PART_NUMBER"CH622KMEB02";
"B"
$PN"2"30;
"A"
$PN"1"29;
%"UNIVERSAL_GND"
"1","(-525,5525)","0","pure_quanta_power","I174";
;
CDS_LIB"pure_quanta_power"
HDL_POWER"GND";
"A"30;
%"Q_CAP"
"1","(-525,5900)","0","pure_quanta","I175";
;
LOCATION"C2654"
$SEC"1"
CDS_SEC"1"
MATERIAL"X6S"
TOLERANCE"20%"
VALUE"22UF"
VOLTAGE"4V"
PACK_TYPE"C0402"
CDS_LIB"pure_quanta"
PART_NUMBER"CH622KMEB02";
"B"
$PN"2"30;
"A"
$PN"1"29;
%"Q_CAP"
"1","(-9100,5150)","0","pure_quanta","I18";
;
LOCATION"C2528"
$SEC"1"
CDS_SEC"1"
MATERIAL"X6S"
TOLERANCE"20%"
VALUE"22UF"
VOLTAGE"4V"
PACK_TYPE"C0402"
CDS_LIB"pure_quanta"
PART_NUMBER"CH622KMEB02";
"B"
$PN"2"11;
"A"
$PN"1"14;
%"Q_CAP"
"1","(-8650,4425)","0","pure_quanta","I19";
;
LOCATION"C2536"
$SEC"1"
CDS_SEC"1"
MATERIAL"X6S"
TOLERANCE"20%"
VALUE"22UF"
VOLTAGE"4V"
PACK_TYPE"C0402"
CDS_LIB"pure_quanta"
PART_NUMBER"CH622KMEB02";
"B"
$PN"2"13;
"A"
$PN"1"12;
%"UNIVERSAL_POWER"
"1","(-9075,1150)","0","pure_quanta_power","I2";
;
HDL_POWER"PVDDCR_SOC_P0"
CDS_LIB"pure_quanta_power";
"A"4;
%"Q_CAP"
"1","(-8650,5150)","0","pure_quanta","I20";
;
LOCATION"C2535"
$SEC"1"
CDS_SEC"1"
MATERIAL"X6S"
TOLERANCE"20%"
VALUE"22UF"
VOLTAGE"4V"
PACK_TYPE"C0402"
CDS_LIB"pure_quanta"
PART_NUMBER"CH622KMEB02";
"B"
$PN"2"11;
"A"
$PN"1"14;
%"UNIVERSAL_POWER"
"1","(-9100,5425)","0","pure_quanta_power","I21";
;
HDL_POWER"PVDDCR_SOC_P0"
CDS_LIB"pure_quanta_power";
"A"14;
%"Q_CAP"
"1","(-9100,5900)","0","pure_quanta","I22";
;
LOCATION"C2527"
$SEC"1"
CDS_SEC"1"
MATERIAL"X6S"
TOLERANCE"20%"
VALUE"22UF"
VOLTAGE"4V"
PACK_TYPE"C0402"
CDS_LIB"pure_quanta"
PART_NUMBER"CH622KMEB02";
"B"
$PN"2"16;
"A"
$PN"1"15;
%"UNIVERSAL_POWER"
"1","(-9100,6175)","0","pure_quanta_power","I23";
;
HDL_POWER"PVDDCR_SOC_P0"
CDS_LIB"pure_quanta_power";
"A"15;
%"Q_CAP"
"1","(-8650,5900)","0","pure_quanta","I24";
;
LOCATION"C2534"
$SEC"1"
CDS_SEC"1"
MATERIAL"X6S"
TOLERANCE"20%"
VALUE"22UF"
VOLTAGE"4V"
PACK_TYPE"C0402"
CDS_LIB"pure_quanta"
PART_NUMBER"CH622KMEB02";
"B"
$PN"2"16;
"A"
$PN"1"15;
%"Q_CAP"
"1","(-8175,875)","0","pure_quanta","I25";
;
LOCATION"C3927"
$SEC"1"
CDS_SEC"1"
MATERIAL"X6S"
TOLERANCE"20%"
VALUE"22UF"
VOLTAGE"4V"
PACK_TYPE"C0402"
CDS_LIB"pure_quanta"
PART_NUMBER"CH622KMEB02";
"B"
$PN"2"1;
"A"
$PN"1"4;
%"Q_CAP"
"1","(-7725,875)","0","pure_quanta","I26";
;
LOCATION"C3928"
$SEC"1"
CDS_SEC"1"
MATERIAL"X6S"
TOLERANCE"20%"
VALUE"22UF"
VOLTAGE"4V"
PACK_TYPE"C0402"
CDS_LIB"pure_quanta"
PART_NUMBER"CH622KMEB02";
"B"
$PN"2"1;
"A"
$PN"1"4;
%"Q_CAP"
"1","(-7275,875)","0","pure_quanta","I27";
;
LOCATION"C3929"
$SEC"1"
CDS_SEC"1"
MATERIAL"X6S"
TOLERANCE"20%"
VALUE"22UF"
VOLTAGE"4V"
PACK_TYPE"C0402"
CDS_LIB"pure_quanta"
PART_NUMBER"CH622KMEB02";
"B"
$PN"2"1;
"A"
$PN"1"4;
%"Q_CAP"
"1","(-8175,1575)","0","pure_quanta","I28";
;
LOCATION"C2547"
$SEC"1"
CDS_SEC"1"
MATERIAL"X6S"
TOLERANCE"20%"
VALUE"22UF"
VOLTAGE"4V"
PACK_TYPE"C0402"
CDS_LIB"pure_quanta"
PART_NUMBER"CH622KMEB02";
"B"
$PN"2"3;
"A"
$PN"1"2;
%"Q_CAP"
"1","(-7725,1575)","0","pure_quanta","I29";
;
LOCATION"C2554"
$SEC"1"
CDS_SEC"1"
MATERIAL"X6S"
TOLERANCE"20%"
VALUE"22UF"
VOLTAGE"4V"
PACK_TYPE"C0402"
CDS_LIB"pure_quanta"
PART_NUMBER"CH622KMEB02";
"B"
$PN"2"3;
"A"
$PN"1"2;
%"Q_CAP"
"1","(-8625,875)","0","pure_quanta","I3";
;
LOCATION"C3926"
$SEC"1"
CDS_SEC"1"
MATERIAL"X6S"
TOLERANCE"20%"
VALUE"22UF"
VOLTAGE"4V"
PACK_TYPE"C0402"
CDS_LIB"pure_quanta"
PART_NUMBER"CH622KMEB02";
"B"
$PN"2"1;
"A"
$PN"1"4;
%"Q_CAP"
"1","(-7275,1575)","0","pure_quanta","I30";
;
LOCATION"C2561"
$SEC"1"
CDS_SEC"1"
MATERIAL"X6S"
TOLERANCE"20%"
VALUE"22UF"
VOLTAGE"4V"
PACK_TYPE"C0402"
CDS_LIB"pure_quanta"
PART_NUMBER"CH622KMEB02";
"B"
$PN"2"3;
"A"
$PN"1"2;
%"Q_CAP"
"1","(-6825,875)","0","pure_quanta","I31";
;
LOCATION"C3930"
$SEC"1"
CDS_SEC"1"
MATERIAL"X6S"
TOLERANCE"20%"
VALUE"22UF"
VOLTAGE"4V"
PACK_TYPE"C0402"
CDS_LIB"pure_quanta"
PART_NUMBER"CH622KMEB02";
"B"
$PN"2"1;
"A"
$PN"1"4;
%"UNIVERSAL_GND"
"1","(-6375,500)","0","pure_quanta_power","I32";
;
CDS_LIB"pure_quanta_power"
HDL_POWER"GND";
"A"1;
%"Q_CAP"
"1","(-6375,875)","0","pure_quanta","I33";
;
LOCATION"C3931"
$SEC"1"
CDS_SEC"1"
MATERIAL"X6S"
TOLERANCE"20%"
VALUE"22UF"
VOLTAGE"4V"
PACK_TYPE"C0402"
CDS_LIB"pure_quanta"
PART_NUMBER"CH622KMEB02";
"B"
$PN"2"1;
"A"
$PN"1"4;
%"Q_CAP"
"1","(-6825,1575)","0","pure_quanta","I34";
;
LOCATION"C2568"
$SEC"1"
CDS_SEC"1"
MATERIAL"X6S"
TOLERANCE"20%"
VALUE"22UF"
VOLTAGE"4V"
PACK_TYPE"C0402"
CDS_LIB"pure_quanta"
PART_NUMBER"CH622KMEB02";
"B"
$PN"2"3;
"A"
$PN"1"2;
%"Q_CAP"
"1","(-6375,1575)","0","pure_quanta","I35";
;
LOCATION"C2575"
$SEC"1"
CDS_SEC"1"
MATERIAL"X6S"
TOLERANCE"20%"
VALUE"22UF"
VOLTAGE"4V"
PACK_TYPE"C0402"
CDS_LIB"pure_quanta"
PART_NUMBER"CH622KMEB02";
"B"
$PN"2"3;
"A"
$PN"1"2;
%"Q_CAP"
"1","(-8175,2300)","0","pure_quanta","I36";
;
LOCATION"C2546"
$SEC"1"
CDS_SEC"1"
MATERIAL"X6S"
TOLERANCE"20%"
VALUE"22UF"
VOLTAGE"4V"
PACK_TYPE"C0402"
CDS_LIB"pure_quanta"
PART_NUMBER"CH622KMEB02";
"B"
$PN"2"7;
"A"
$PN"1"6;
%"Q_CAP"
"1","(-8175,3000)","0","pure_quanta","I37";
;
LOCATION"C2545"
$SEC"1"
CDS_SEC"1"
MATERIAL"X6S"
TOLERANCE"20%"
VALUE"22UF"
VOLTAGE"4V"
PACK_TYPE"C0402"
CDS_LIB"pure_quanta"
PART_NUMBER"CH622KMEB02";
"B"
$PN"2"5;
"A"
$PN"1"10;
%"Q_CAP"
"1","(-7725,2300)","0","pure_quanta","I38";
;
LOCATION"C2553"
$SEC"1"
CDS_SEC"1"
MATERIAL"X6S"
TOLERANCE"20%"
VALUE"22UF"
VOLTAGE"4V"
PACK_TYPE"C0402"
CDS_LIB"pure_quanta"
PART_NUMBER"CH622KMEB02";
"B"
$PN"2"7;
"A"
$PN"1"6;
%"Q_CAP"
"1","(-7275,2300)","0","pure_quanta","I39";
;
LOCATION"C2560"
$SEC"1"
CDS_SEC"1"
MATERIAL"X6S"
TOLERANCE"20%"
VALUE"22UF"
VOLTAGE"4V"
PACK_TYPE"C0402"
CDS_LIB"pure_quanta"
PART_NUMBER"CH622KMEB02";
"B"
$PN"2"7;
"A"
$PN"1"6;
%"Q_CAP"
"1","(-9075,1575)","0","pure_quanta","I4";
;
LOCATION"C2533"
$SEC"1"
CDS_SEC"1"
MATERIAL"X6S"
TOLERANCE"20%"
VALUE"22UF"
VOLTAGE"4V"
PACK_TYPE"C0402"
CDS_LIB"pure_quanta"
PART_NUMBER"CH622KMEB02";
"B"
$PN"2"3;
"A"
$PN"1"2;
%"Q_CAP"
"1","(-7725,3000)","0","pure_quanta","I40";
;
LOCATION"C2552"
$SEC"1"
CDS_SEC"1"
MATERIAL"X6S"
TOLERANCE"20%"
VALUE"22UF"
VOLTAGE"4V"
PACK_TYPE"C0402"
CDS_LIB"pure_quanta"
PART_NUMBER"CH622KMEB02";
"B"
$PN"2"5;
"A"
$PN"1"10;
%"Q_CAP"
"1","(-7275,3000)","0","pure_quanta","I41";
;
LOCATION"C2559"
$SEC"1"
CDS_SEC"1"
MATERIAL"X6S"
TOLERANCE"20%"
VALUE"22UF"
VOLTAGE"4V"
PACK_TYPE"C0402"
CDS_LIB"pure_quanta"
PART_NUMBER"CH622KMEB02";
"B"
$PN"2"5;
"A"
$PN"1"10;
%"Q_CAP"
"1","(-8175,3725)","0","pure_quanta","I42";
;
LOCATION"C2544"
$SEC"1"
CDS_SEC"1"
MATERIAL"X6S"
TOLERANCE"20%"
VALUE"22UF"
VOLTAGE"4V"
PACK_TYPE"C0402"
CDS_LIB"pure_quanta"
PART_NUMBER"CH622KMEB02";
"B"
$PN"2"9;
"A"
$PN"1"8;
%"Q_CAP"
"1","(-7725,3725)","0","pure_quanta","I43";
;
LOCATION"C2551"
$SEC"1"
CDS_SEC"1"
MATERIAL"X6S"
TOLERANCE"20%"
VALUE"22UF"
VOLTAGE"4V"
PACK_TYPE"C0402"
CDS_LIB"pure_quanta"
PART_NUMBER"CH622KMEB02";
"B"
$PN"2"9;
"A"
$PN"1"8;
%"Q_CAP"
"1","(-7275,3725)","0","pure_quanta","I44";
;
LOCATION"C2558"
$SEC"1"
CDS_SEC"1"
MATERIAL"X6S"
TOLERANCE"20%"
VALUE"22UF"
VOLTAGE"4V"
PACK_TYPE"C0402"
CDS_LIB"pure_quanta"
PART_NUMBER"CH622KMEB02";
"B"
$PN"2"9;
"A"
$PN"1"8;
%"Q_CAP"
"1","(-6825,2300)","0","pure_quanta","I45";
;
LOCATION"C2567"
$SEC"1"
CDS_SEC"1"
MATERIAL"X6S"
TOLERANCE"20%"
VALUE"22UF"
VOLTAGE"4V"
PACK_TYPE"C0402"
CDS_LIB"pure_quanta"
PART_NUMBER"CH622KMEB02";
"B"
$PN"2"7;
"A"
$PN"1"6;
%"Q_CAP"
"1","(-6825,3000)","0","pure_quanta","I46";
;
LOCATION"C2566"
$SEC"1"
CDS_SEC"1"
MATERIAL"X6S"
TOLERANCE"20%"
VALUE"22UF"
VOLTAGE"4V"
PACK_TYPE"C0402"
CDS_LIB"pure_quanta"
PART_NUMBER"CH622KMEB02";
"B"
$PN"2"5;
"A"
$PN"1"10;
%"Q_CAP"
"1","(-6375,2300)","0","pure_quanta","I47";
;
LOCATION"C2574"
$SEC"1"
CDS_SEC"1"
MATERIAL"X6S"
TOLERANCE"20%"
VALUE"22UF"
VOLTAGE"4V"
PACK_TYPE"C0402"
CDS_LIB"pure_quanta"
PART_NUMBER"CH622KMEB02";
"B"
$PN"2"7;
"A"
$PN"1"6;
%"Q_CAP"
"1","(-6375,3000)","0","pure_quanta","I48";
;
LOCATION"C2573"
$SEC"1"
CDS_SEC"1"
MATERIAL"X6S"
TOLERANCE"20%"
VALUE"22UF"
VOLTAGE"4V"
PACK_TYPE"C0402"
CDS_LIB"pure_quanta"
PART_NUMBER"CH622KMEB02";
"B"
$PN"2"5;
"A"
$PN"1"10;
%"Q_CAP"
"1","(-6825,3725)","0","pure_quanta","I49";
;
LOCATION"C2565"
$SEC"1"
CDS_SEC"1"
MATERIAL"X6S"
TOLERANCE"20%"
VALUE"22UF"
VOLTAGE"4V"
PACK_TYPE"C0402"
CDS_LIB"pure_quanta"
PART_NUMBER"CH622KMEB02";
"B"
$PN"2"9;
"A"
$PN"1"8;
%"UNIVERSAL_POWER"
"1","(-9075,1850)","0","pure_quanta_power","I5";
;
HDL_POWER"PVDDCR_SOC_P0"
CDS_LIB"pure_quanta_power";
"A"2;
%"Q_CAP"
"1","(-6375,3725)","0","pure_quanta","I50";
;
LOCATION"C2572"
$SEC"1"
CDS_SEC"1"
MATERIAL"X6S"
TOLERANCE"20%"
VALUE"22UF"
VOLTAGE"4V"
PACK_TYPE"C0402"
CDS_LIB"pure_quanta"
PART_NUMBER"CH622KMEB02";
"B"
$PN"2"9;
"A"
$PN"1"8;
%"Q_CAP"
"1","(-5925,1575)","0","pure_quanta","I51";
;
LOCATION"C2582"
$SEC"1"
CDS_SEC"1"
MATERIAL"X6S"
TOLERANCE"20%"
VALUE"22UF"
VOLTAGE"4V"
PACK_TYPE"C0402"
CDS_LIB"pure_quanta"
PART_NUMBER"CH622KMEB02";
"B"
$PN"2"3;
"A"
$PN"1"2;
%"Q_CAP"
"1","(-5475,1575)","0","pure_quanta","I52";
;
LOCATION"C2589"
$SEC"1"
CDS_SEC"1"
MATERIAL"X6S"
TOLERANCE"20%"
VALUE"22UF"
VOLTAGE"4V"
PACK_TYPE"C0402"
CDS_LIB"pure_quanta"
PART_NUMBER"CH622KMEB02";
"B"
$PN"2"3;
"A"
$PN"1"2;
%"Q_CAP"
"1","(-4500,800)","0","pure_quanta","I53";
;
LOCATION"C3932"
$SEC"1"
CDS_SEC"1"
MATERIAL"X6S"
TOLERANCE"20%"
VALUE"22UF"
VOLTAGE"4V"
PACK_TYPE"C0402"
CDS_LIB"pure_quanta"
PART_NUMBER"CH622KMEB02";
"B"
$PN"2"26;
"A"
$PN"1"25;
%"UNIVERSAL_POWER"
"1","(-4500,1075)","0","pure_quanta_power","I54";
;
HDL_POWER"PVDD11_S3_P0"
CDS_LIB"pure_quanta_power";
"A"25;
%"UNIVERSAL_GND"
"1","(-5075,1200)","0","pure_quanta_power","I55";
;
CDS_LIB"pure_quanta_power"
HDL_POWER"GND";
"A"3;
%"Q_CAP"
"1","(-5075,1575)","0","pure_quanta","I56";
;
LOCATION"C2596"
$SEC"1"
CDS_SEC"1"
MATERIAL"X6S"
TOLERANCE"20%"
VALUE"22UF"
VOLTAGE"4V"
PACK_TYPE"C0402"
CDS_LIB"pure_quanta"
PART_NUMBER"CH622KMEB02";
"B"
$PN"2"3;
"A"
$PN"1"2;
%"UNIVERSAL_GND"
"1","(-5075,1925)","0","pure_quanta_power","I57";
;
CDS_LIB"pure_quanta_power"
HDL_POWER"GND";
"A"7;
%"Q_CAP"
"1","(-4500,1400)","0","pure_quanta","I58";
;
LOCATION"C2603"
$SEC"1"
CDS_SEC"1"
MATERIAL"X6S"
TOLERANCE"20%"
VALUE"22UF"
VOLTAGE"4V"
PACK_TYPE"C0402"
CDS_LIB"pure_quanta"
PART_NUMBER"CH622KMEB02";
"B"
$PN"2"24;
"A"
$PN"1"23;
%"UNIVERSAL_POWER"
"1","(-4500,1675)","0","pure_quanta_power","I59";
;
HDL_POWER"PVDD11_S3_P0"
CDS_LIB"pure_quanta_power";
"A"23;
%"Q_CAP"
"1","(-8625,1575)","0","pure_quanta","I6";
;
LOCATION"C2540"
$SEC"1"
CDS_SEC"1"
MATERIAL"X6S"
TOLERANCE"20%"
VALUE"22UF"
VOLTAGE"4V"
PACK_TYPE"C0402"
CDS_LIB"pure_quanta"
PART_NUMBER"CH622KMEB02";
"B"
$PN"2"3;
"A"
$PN"1"2;
%"Q_CAP"
"1","(-4500,2000)","0","pure_quanta","I60";
;
LOCATION"C2602"
$SEC"1"
CDS_SEC"1"
MATERIAL"X6S"
TOLERANCE"20%"
VALUE"22UF"
VOLTAGE"4V"
PACK_TYPE"C0402"
CDS_LIB"pure_quanta"
PART_NUMBER"CH622KMEB02";
"B"
$PN"2"22;
"A"
$PN"1"21;
%"Q_CAP"
"1","(-5925,2300)","0","pure_quanta","I61";
;
LOCATION"C2581"
$SEC"1"
CDS_SEC"1"
MATERIAL"X6S"
TOLERANCE"20%"
VALUE"22UF"
VOLTAGE"4V"
PACK_TYPE"C0402"
CDS_LIB"pure_quanta"
PART_NUMBER"CH622KMEB02";
"B"
$PN"2"7;
"A"
$PN"1"6;
%"Q_CAP"
"1","(-5925,3000)","0","pure_quanta","I62";
;
LOCATION"C2580"
$SEC"1"
CDS_SEC"1"
MATERIAL"X6S"
TOLERANCE"20%"
VALUE"22UF"
VOLTAGE"4V"
PACK_TYPE"C0402"
CDS_LIB"pure_quanta"
PART_NUMBER"CH622KMEB02";
"B"
$PN"2"5;
"A"
$PN"1"10;
%"Q_CAP"
"1","(-5475,2300)","0","pure_quanta","I63";
;
LOCATION"C2588"
$SEC"1"
CDS_SEC"1"
MATERIAL"X6S"
TOLERANCE"20%"
VALUE"22UF"
VOLTAGE"4V"
PACK_TYPE"C0402"
CDS_LIB"pure_quanta"
PART_NUMBER"CH622KMEB02";
"B"
$PN"2"7;
"A"
$PN"1"6;
%"Q_CAP"
"1","(-5475,3000)","0","pure_quanta","I64";
;
LOCATION"C2587"
$SEC"1"
CDS_SEC"1"
MATERIAL"X6S"
TOLERANCE"20%"
VALUE"22UF"
VOLTAGE"4V"
PACK_TYPE"C0402"
CDS_LIB"pure_quanta"
PART_NUMBER"CH622KMEB02";
"B"
$PN"2"5;
"A"
$PN"1"10;
%"Q_CAP"
"1","(-5925,3725)","0","pure_quanta","I65";
;
LOCATION"C2579"
$SEC"1"
CDS_SEC"1"
MATERIAL"X6S"
TOLERANCE"20%"
VALUE"22UF"
VOLTAGE"4V"
PACK_TYPE"C0402"
CDS_LIB"pure_quanta"
PART_NUMBER"CH622KMEB02";
"B"
$PN"2"9;
"A"
$PN"1"8;
%"Q_CAP"
"1","(-5475,3725)","0","pure_quanta","I66";
;
LOCATION"C2586"
$SEC"1"
CDS_SEC"1"
MATERIAL"X6S"
TOLERANCE"20%"
VALUE"22UF"
VOLTAGE"4V"
PACK_TYPE"C0402"
CDS_LIB"pure_quanta"
PART_NUMBER"CH622KMEB02";
"B"
$PN"2"9;
"A"
$PN"1"8;
%"Q_CAP"
"1","(-5075,2300)","0","pure_quanta","I67";
;
LOCATION"C2595"
$SEC"1"
CDS_SEC"1"
MATERIAL"X6S"
TOLERANCE"20%"
VALUE"22UF"
VOLTAGE"4V"
PACK_TYPE"C0402"
CDS_LIB"pure_quanta"
PART_NUMBER"CH622KMEB02";
"B"
$PN"2"7;
"A"
$PN"1"6;
%"UNIVERSAL_GND"
"1","(-5075,2625)","0","pure_quanta_power","I68";
;
CDS_LIB"pure_quanta_power"
HDL_POWER"GND";
"A"5;
%"Q_CAP"
"1","(-5075,3000)","0","pure_quanta","I69";
;
LOCATION"C2594"
$SEC"1"
CDS_SEC"1"
MATERIAL"X6S"
TOLERANCE"20%"
VALUE"22UF"
VOLTAGE"4V"
PACK_TYPE"C0402"
CDS_LIB"pure_quanta"
PART_NUMBER"CH622KMEB02";
"B"
$PN"2"5;
"A"
$PN"1"10;
%"Q_CAP"
"1","(-9075,2300)","0","pure_quanta","I7";
;
LOCATION"C2532"
$SEC"1"
CDS_SEC"1"
MATERIAL"X6S"
TOLERANCE"20%"
VALUE"22UF"
VOLTAGE"4V"
PACK_TYPE"C0402"
CDS_LIB"pure_quanta"
PART_NUMBER"CH622KMEB02";
"B"
$PN"2"7;
"A"
$PN"1"6;
%"UNIVERSAL_POWER"
"1","(-4500,2275)","0","pure_quanta_power","I70";
;
HDL_POWER"PVDD11_S3_P0"
CDS_LIB"pure_quanta_power";
"A"21;
%"Q_CAP"
"1","(-4500,2625)","0","pure_quanta","I71";
;
LOCATION"C2601"
$SEC"1"
CDS_SEC"1"
MATERIAL"X6S"
TOLERANCE"20%"
VALUE"22UF"
VOLTAGE"4V"
PACK_TYPE"C0402"
CDS_LIB"pure_quanta"
PART_NUMBER"CH622KMEB02";
"B"
$PN"2"20;
"A"
$PN"1"19;
%"UNIVERSAL_POWER"
"1","(-4500,2900)","0","pure_quanta_power","I72";
;
HDL_POWER"PVDD11_S3_P0"
CDS_LIB"pure_quanta_power";
"A"19;
%"UNIVERSAL_GND"
"1","(-5075,3350)","0","pure_quanta_power","I73";
;
CDS_LIB"pure_quanta_power"
HDL_POWER"GND";
"A"9;
%"Q_CAP"
"1","(-5075,3725)","0","pure_quanta","I74";
;
LOCATION"C2593"
$SEC"1"
CDS_SEC"1"
MATERIAL"X6S"
TOLERANCE"20%"
VALUE"22UF"
VOLTAGE"4V"
PACK_TYPE"C0402"
CDS_LIB"pure_quanta"
PART_NUMBER"CH622KMEB02";
"B"
$PN"2"9;
"A"
$PN"1"8;
%"UNIVERSAL_GND"
"1","(-5100,4050)","0","pure_quanta_power","I75";
;
CDS_LIB"pure_quanta_power"
HDL_POWER"GND";
"A"13;
%"Q_CAP"
"1","(-4500,3275)","0","pure_quanta","I76";
;
LOCATION"C2600"
$SEC"1"
CDS_SEC"1"
MATERIAL"X6S"
TOLERANCE"20%"
VALUE"22UF"
VOLTAGE"4V"
PACK_TYPE"C0402"
CDS_LIB"pure_quanta"
PART_NUMBER"CH622KMEB02";
"B"
$PN"2"18;
"A"
$PN"1"17;
%"UNIVERSAL_POWER"
"1","(-4500,3550)","0","pure_quanta_power","I77";
;
HDL_POWER"PVDD11_S3_P0"
CDS_LIB"pure_quanta_power";
"A"17;
%"Q_CAP"
"1","(-8200,4425)","0","pure_quanta","I78";
;
LOCATION"C2543"
$SEC"1"
CDS_SEC"1"
MATERIAL"X6S"
TOLERANCE"20%"
VALUE"22UF"
VOLTAGE"4V"
PACK_TYPE"C0402"
CDS_LIB"pure_quanta"
PART_NUMBER"CH622KMEB02";
"B"
$PN"2"13;
"A"
$PN"1"12;
%"Q_CAP"
"1","(-8200,5150)","0","pure_quanta","I79";
;
LOCATION"C2542"
$SEC"1"
CDS_SEC"1"
MATERIAL"X6S"
TOLERANCE"20%"
VALUE"22UF"
VOLTAGE"4V"
PACK_TYPE"C0402"
CDS_LIB"pure_quanta"
PART_NUMBER"CH622KMEB02";
"B"
$PN"2"11;
"A"
$PN"1"14;
%"UNIVERSAL_POWER"
"1","(-9075,2575)","0","pure_quanta_power","I8";
;
HDL_POWER"PVDDCR_SOC_P0"
CDS_LIB"pure_quanta_power";
"A"6;
%"Q_CAP"
"1","(-7750,4425)","0","pure_quanta","I80";
;
LOCATION"C2550"
$SEC"1"
CDS_SEC"1"
MATERIAL"X6S"
TOLERANCE"20%"
VALUE"22UF"
VOLTAGE"4V"
PACK_TYPE"C0402"
CDS_LIB"pure_quanta"
PART_NUMBER"CH622KMEB02";
"B"
$PN"2"13;
"A"
$PN"1"12;
%"Q_CAP"
"1","(-7750,5150)","0","pure_quanta","I81";
;
LOCATION"C2549"
$SEC"1"
CDS_SEC"1"
MATERIAL"X6S"
TOLERANCE"20%"
VALUE"22UF"
VOLTAGE"4V"
PACK_TYPE"C0402"
CDS_LIB"pure_quanta"
PART_NUMBER"CH622KMEB02";
"B"
$PN"2"11;
"A"
$PN"1"14;
%"Q_CAP"
"1","(-7300,4425)","0","pure_quanta","I82";
;
LOCATION"C2557"
$SEC"1"
CDS_SEC"1"
MATERIAL"X6S"
TOLERANCE"20%"
VALUE"22UF"
VOLTAGE"4V"
PACK_TYPE"C0402"
CDS_LIB"pure_quanta"
PART_NUMBER"CH622KMEB02";
"B"
$PN"2"13;
"A"
$PN"1"12;
%"Q_CAP"
"1","(-7300,5150)","0","pure_quanta","I83";
;
LOCATION"C2556"
$SEC"1"
CDS_SEC"1"
MATERIAL"X6S"
TOLERANCE"20%"
VALUE"22UF"
VOLTAGE"4V"
PACK_TYPE"C0402"
CDS_LIB"pure_quanta"
PART_NUMBER"CH622KMEB02";
"B"
$PN"2"11;
"A"
$PN"1"14;
%"Q_CAP"
"1","(-8200,5900)","0","pure_quanta","I84";
;
LOCATION"C2541"
$SEC"1"
CDS_SEC"1"
MATERIAL"X6S"
TOLERANCE"20%"
VALUE"22UF"
VOLTAGE"4V"
PACK_TYPE"C0402"
CDS_LIB"pure_quanta"
PART_NUMBER"CH622KMEB02";
"B"
$PN"2"16;
"A"
$PN"1"15;
%"Q_CAP"
"1","(-7750,5900)","0","pure_quanta","I85";
;
LOCATION"C2548"
$SEC"1"
CDS_SEC"1"
MATERIAL"X6S"
TOLERANCE"20%"
VALUE"22UF"
VOLTAGE"4V"
PACK_TYPE"C0402"
CDS_LIB"pure_quanta"
PART_NUMBER"CH622KMEB02";
"B"
$PN"2"16;
"A"
$PN"1"15;
%"Q_CAP"
"1","(-7300,5900)","0","pure_quanta","I86";
;
LOCATION"C2555"
$SEC"1"
CDS_SEC"1"
MATERIAL"X6S"
TOLERANCE"20%"
VALUE"22UF"
VOLTAGE"4V"
PACK_TYPE"C0402"
CDS_LIB"pure_quanta"
PART_NUMBER"CH622KMEB02";
"B"
$PN"2"16;
"A"
$PN"1"15;
%"Q_CAP"
"1","(-6850,4425)","0","pure_quanta","I87";
;
LOCATION"C2564"
$SEC"1"
CDS_SEC"1"
MATERIAL"X6S"
TOLERANCE"20%"
VALUE"22UF"
VOLTAGE"4V"
PACK_TYPE"C0402"
CDS_LIB"pure_quanta"
PART_NUMBER"CH622KMEB02";
"B"
$PN"2"13;
"A"
$PN"1"12;
%"Q_CAP"
"1","(-6850,5150)","0","pure_quanta","I88";
;
LOCATION"C2563"
$SEC"1"
CDS_SEC"1"
MATERIAL"X6S"
TOLERANCE"20%"
VALUE"22UF"
VOLTAGE"4V"
PACK_TYPE"C0402"
CDS_LIB"pure_quanta"
PART_NUMBER"CH622KMEB02";
"B"
$PN"2"11;
"A"
$PN"1"14;
%"Q_CAP"
"1","(-6400,4425)","0","pure_quanta","I89";
;
LOCATION"C2571"
$SEC"1"
CDS_SEC"1"
MATERIAL"X6S"
TOLERANCE"20%"
VALUE"22UF"
VOLTAGE"4V"
PACK_TYPE"C0402"
CDS_LIB"pure_quanta"
PART_NUMBER"CH622KMEB02";
"B"
$PN"2"13;
"A"
$PN"1"12;
%"Q_CAP"
"1","(-9075,3000)","0","pure_quanta","I9";
;
LOCATION"C2531"
$SEC"1"
CDS_SEC"1"
MATERIAL"X6S"
TOLERANCE"20%"
VALUE"22UF"
VOLTAGE"4V"
PACK_TYPE"C0402"
CDS_LIB"pure_quanta"
PART_NUMBER"CH622KMEB02";
"B"
$PN"2"5;
"A"
$PN"1"10;
%"Q_CAP"
"1","(-6400,5150)","0","pure_quanta","I90";
;
LOCATION"C2570"
$SEC"1"
CDS_SEC"1"
MATERIAL"X6S"
TOLERANCE"20%"
VALUE"22UF"
VOLTAGE"4V"
PACK_TYPE"C0402"
CDS_LIB"pure_quanta"
PART_NUMBER"CH622KMEB02";
"B"
$PN"2"11;
"A"
$PN"1"14;
%"Q_CAP"
"1","(-6850,5900)","0","pure_quanta","I91";
;
LOCATION"C2562"
$SEC"1"
CDS_SEC"1"
MATERIAL"X6S"
TOLERANCE"20%"
VALUE"22UF"
VOLTAGE"4V"
PACK_TYPE"C0402"
CDS_LIB"pure_quanta"
PART_NUMBER"CH622KMEB02";
"B"
$PN"2"16;
"A"
$PN"1"15;
%"Q_CAP"
"1","(-6400,5900)","0","pure_quanta","I92";
;
LOCATION"C2569"
$SEC"1"
CDS_SEC"1"
MATERIAL"X6S"
TOLERANCE"20%"
VALUE"22UF"
VOLTAGE"4V"
PACK_TYPE"C0402"
CDS_LIB"pure_quanta"
PART_NUMBER"CH622KMEB02";
"B"
$PN"2"16;
"A"
$PN"1"15;
%"Q_CAP"
"1","(-5950,4425)","0","pure_quanta","I93";
;
LOCATION"C2578"
$SEC"1"
CDS_SEC"1"
MATERIAL"X6S"
TOLERANCE"20%"
VALUE"22UF"
VOLTAGE"4V"
PACK_TYPE"C0402"
CDS_LIB"pure_quanta"
PART_NUMBER"CH622KMEB02";
"B"
$PN"2"13;
"A"
$PN"1"12;
%"Q_CAP"
"1","(-5950,5150)","0","pure_quanta","I94";
;
LOCATION"C2577"
$SEC"1"
CDS_SEC"1"
MATERIAL"X6S"
TOLERANCE"20%"
VALUE"22UF"
VOLTAGE"4V"
PACK_TYPE"C0402"
CDS_LIB"pure_quanta"
PART_NUMBER"CH622KMEB02";
"B"
$PN"2"11;
"A"
$PN"1"14;
%"Q_CAP"
"1","(-5500,4425)","0","pure_quanta","I95";
;
LOCATION"C2585"
$SEC"1"
CDS_SEC"1"
MATERIAL"X6S"
TOLERANCE"20%"
VALUE"22UF"
VOLTAGE"4V"
PACK_TYPE"C0402"
CDS_LIB"pure_quanta"
PART_NUMBER"CH622KMEB02";
"B"
$PN"2"13;
"A"
$PN"1"12;
%"Q_CAP"
"1","(-5500,5150)","0","pure_quanta","I96";
;
LOCATION"C2584"
$SEC"1"
CDS_SEC"1"
MATERIAL"X6S"
TOLERANCE"20%"
VALUE"22UF"
VOLTAGE"4V"
PACK_TYPE"C0402"
CDS_LIB"pure_quanta"
PART_NUMBER"CH622KMEB02";
"B"
$PN"2"11;
"A"
$PN"1"14;
%"Q_CAP"
"1","(-5950,5900)","0","pure_quanta","I97";
;
LOCATION"C2576"
$SEC"1"
CDS_SEC"1"
MATERIAL"X6S"
TOLERANCE"20%"
VALUE"22UF"
VOLTAGE"4V"
PACK_TYPE"C0402"
CDS_LIB"pure_quanta"
PART_NUMBER"CH622KMEB02";
"B"
$PN"2"16;
"A"
$PN"1"15;
%"Q_CAP"
"1","(-5500,5900)","0","pure_quanta","I98";
;
LOCATION"C2583"
$SEC"1"
CDS_SEC"1"
MATERIAL"X6S"
TOLERANCE"20%"
VALUE"22UF"
VOLTAGE"4V"
PACK_TYPE"C0402"
CDS_LIB"pure_quanta"
PART_NUMBER"CH622KMEB02";
"B"
$PN"2"16;
"A"
$PN"1"15;
%"Q_CAP"
"1","(-5100,4425)","0","pure_quanta","I99";
;
LOCATION"C2592"
$SEC"1"
CDS_SEC"1"
MATERIAL"X6S"
TOLERANCE"20%"
VALUE"22UF"
VOLTAGE"4V"
PACK_TYPE"C0402"
CDS_LIB"pure_quanta"
PART_NUMBER"CH622KMEB02";
"B"
$PN"2"13;
"A"
$PN"1"12;
END.
